# SCM (Grand Teton) — schematic parts with pin connectivity, parts 1361–1376 of 1428; source: Cadence DE-HDL packaged netlist (pstxprt.dat, pstxnet.dat, pstchip.dat)

U5  AST2600A3GP  AST2600A3-GP IC  pkg BGA624_0-8_21X21XA  page 12  (pins 325-624 of 624)
  H1  \ma14||mact#\  OUT  = M_BMC_DDR4_MACT_N
  H2  \mcs#\  OUT  = M_BMC_DDR4_MCS_N
  H3  MA3  OUT  = M_BMC_DDR4_MA<3>
  H4  GND_H4  POWER  = GND
  H5  MBA1  OUT  = M_BMC_DDR4_MBA1
  H6  MVDD_H6  POWER  = P1V2_AUX
  H8  PV18D_H8  POWER  = P1V8_AUX
  H9  GND_H9  POWER  = GND
  H10  GND_H10  POWER  = GND
  H11  GND_H11  POWER  = GND
  H12  PV18D_RGM_H12  POWER  = P1V8_AUX
  H13  GND_H13  POWER  = GND
  H14  PLLAHVDD  POWER  = P3V3_STBY_PLLAHVDD
  H15  PV33D_H15  POWER  = P3V3_AUX
  H16  PV33D_H16  POWER  = P3V3_AUX
  H17  PV33D_H17  POWER  = P3V3_AUX
  H18  SD2VDD_H18  POWER  = P3V3_P1V8_SD2VDD
  H19  SD2VDD_H19  POWER  = P3V3_P1V8_SD2VDD
  H21  SD1VDD_H21  POWER  = P3V3_P1V8_SD1VDD
  H22  \rgmii3txd0||rmii3txd0||gpioc2\  BI  = FM_BMC_CPU_FBRK_OUT_N
  H23  \rgmii3txd1||rmii3txd1||gpioc3\  BI  = RST_SGPIO_RESET_BMC_N
  H24  \rgmii3txck||rmii3rclko||gpioc0\  BI  = RST_PLTRST_R_N
  H25  \gpiob6||txd4\  BI  = FM_ESPI_PLD_R1_EN
  H26  \gpiob2||salt3\  BI  = SMB_BMC_ALERT3_R_N
  J1  MODT  OUT  = M_BMC_DDR4_MODT
  J2  GND_J2  POWER  = GND
  J3  MA4  OUT  = M_BMC_DDR4_MA<4>
  J4  \mcas#\  OUT  = M_BMC_DDR4_MCAS_N
  J5  \mras#\  OUT  = M_BMC_DDR4_MRAS_N
  J6  MVDD_J6  POWER  = P1V2_AUX
  J8  PV18D_J8  POWER  = P1V8_AUX
  J9  DPLLAVDD  POWER  = P1V0_STBY_PLAVDD
  J10  USB2AV33  POWER  = P3V3_BMC_USB2AV33
  J11  GND_J11  POWER  = GND
  J12  PV18D_RGM_J12  POWER  = P1V8_AUX
  J13  GND_J13  POWER  = GND
  J14  GND_J14  POWER  = GND
  J15  GND_J15  POWER  = GND
  J16  GND_J16  POWER  = GND
  J17  GND_J17  POWER  = GND
  J18  GND_J18  POWER  = GND
  J19  GND_J19  POWER  = GND
  J21  RVDD_J21  POWER  = P3V3_P2V5_P1V8_RVDD
  J22  \rgmii3txctl||rmii3txen||gpioc1\  BI  = FM_CPU_RMCA_CATERR_LVT3_R_N
  J23  \gpiob4||mdc2\  BI  = FM_BMC_MUX_CS_SPI_SEL_0
  J24  \gpiob7||rxd4\  BI  = IRQ_BMC_CPU_NMI
  J25  \gpiob3||salt4\  BI  = SMB_BMC_ALERT4_R_N
  J26  \gpiob0||salt1\  BI  = FM_ME_BT_DONE
  K1  \mck#\  OUT  = M_BMC_DDR4_MCLK_DN
  K2  MCK  OUT  = M_BMC_DDR4_MCLK_DP
  K3  MA13  OUT  = M_BMC_DDR4_MA<13>
  K4  GND_K4  POWER  = GND
  K5  MA1  OUT  = M_BMC_DDR4_MA<1>
  K6  MVDD_K6  POWER  = P1V2_AUX
  K8  GND_K8  POWER  = GND
  K9  GND_K9  POWER  = GND
  K10  USB2AV18  POWER  = P1V8_BMC_USB2AV18
  K11  PV33D_RGM_K11  POWER  = P3V3_RGM
  K12  PV33D_RGM_K12  POWER  = P3V3_RGM
  K13  GND_K13  POWER  = GND
  K14  GND_K14  POWER  = GND
  K15  GND_K15  POWER  = GND
  K16  IV12D_K16  POWER  = P1V2_AUX
  K17  IV12D_K17  POWER  = P1V2_AUX
  K18  IV12D_K18  POWER  = P1V2_AUX
  K19  IV12D_K19  POWER  = P1V2_AUX
  K21  RVDD_K21  POWER  = P3V3_P2V5_P1V8_RVDD
  K22  GND_K22  POWER  = GND
  K23  \gpiob1||salt2\  BI  = VOL_SEN_ALERT_R
  K24  \gpioa3||sda12||mdio4\  BI  = SMB_BMC_MM12_R_SDA
  K25  \gpioa7||mac4link||sda14||sgpm2i||sgps2i1\  BI  = SMB_BMC_MM14_R_SDA
  K26  \gpioa4||mac1link||scl13||sgpm2ck||sgps2ck\  BI  = SMB_BMC_MM13_R_SCL
  L1  MA5  OUT  = M_BMC_DDR4_MA<5>
  L2  GND_L2  POWER  = GND
  L3  \mreset#\  OUT  = M_BMC_DDR4_RST_N
  L4  MA12  OUT  = M_BMC_DDR4_MA<12>
  L5  MCKE  OUT  = M_BMC_DDR4_MCKE
  L6  MVDD_L6  POWER  = P1V2_AUX
  L8  GND_L8  POWER  = GND
  L9  IV10D_L9  POWER  = P1V0_AUX
  L10  IV10D_L10  POWER  = P1V0_AUX
  L11  GND_L11  POWER  = GND
  L12  GND_L12  POWER  = GND
  L13  PV18D_SLI_L13  POWER  = P1V8_AUX
  L14  IV12D_L14  POWER  = P1V2_AUX
  L15  GND_L15  POWER  = GND
  L16  GND_L16  POWER  = GND
  L17  GND_L17  POWER  = GND
  L18  GND_L18  POWER  = GND
  L19  GND_L19  POWER  = GND
  L21  IV12D_L21  POWER  = P1V2_AUX
  L22  RVDD_L22  POWER  = P3V3_P2V5_P1V8_RVDD
  L23  \gpioa6||mac3link||scl14||sgpm2o||sgps2i0\  BI  = SMB_BMC_MM14_R_SCL
  L24  \gpioa5||mac2link||sda13||sgpm2ld||sgps2ld\  BI  = SMB_BMC_MM13_R_SDA
  L25  GND_L25  POWER  = GND
  L26  \gpioa2||scl12||mdc4\  BI  = SMB_BMC_MM12_R_SCL
  M1  MA8  OUT  = M_BMC_DDR4_MA<8>
  M2  MA7  OUT  = M_BMC_DDR4_MA<7>
  M3  \ma15||mbg1\  OUT  = M_BMC_DDR4_MBG1
  M4  GND_M4  POWER  = GND
  M5  MA6  OUT  = M_BMC_DDR4_MA<6>
  M6  MVDD_CK  POWER  = P1V2_STBY_MVDD_CK
  M8  IV10D_M8  POWER  = P1V0_AUX
  M9  GND_M9  POWER  = GND
  M10  GND_M10  POWER  = GND
  M11  IV10D_M11  POWER  = P1V0_AUX
  M12  GND_M12  POWER  = GND
  M13  PV18D_SLI_M13  POWER  = P1V8_AUX
  M14  IV12D_M14  POWER  = P1V2_AUX
  M15  GND_M15  POWER  = GND
  M16  GND_M16  POWER  = GND
  M17  GND_M17  POWER  = GND
  M18  GND_M18  POWER  = GND
  M19  GND_M19  POWER  = GND
  M21  IV12D_M21  POWER  = P1V2_AUX
  M22  RVDD_M22  POWER  = P3V3_P2V5_P1V8_RVDD
  M23  \gpion5||nrts2\  BI  = LED_POSTCODE_5
  M24  \gpioa0||scl11||mdc3\  BI  = FM_PFR_DSW_PWROK_N
  M25  \gpioa1||sda11||mdio3\  BI  = RST_PFR_OVR_RTC_R
  M26  \gpion7||rxd2\  BI  = LED_POSTCODE_7
  N1  MA9  OUT  = M_BMC_DDR4_MA<9>
  N2  GND_N2  POWER  = GND
  N3  MDM0  OUT  = M_BMC_DDR4_MDM0
  N4  \malert#\  BI  = M_BMC_DDR4_ALERT_N
  N5  AVDDPLL  POWER  = P1V8_STBY_AVDDPLL
  N6  GND_N6  POWER  = GND
  N8  IV10D_N8  POWER  = P1V0_AUX
  N9  GND_N9  POWER  = GND
  N10  GND_N10  POWER  = GND
  N11  IV10D_N11  POWER  = P1V0_AUX
  N12  PV18D_N12  POWER  = P1V8_AUX
  N13  PV18D_SLI_N13  POWER  = P1V8_AUX
  N14  IV12D_N14  POWER  = P1V2_AUX
  N15  GND_N15  POWER  = GND
  N16  GND_N16  POWER  = GND
  N17  GND_N17  POWER  = GND
  N18  GND_N18  POWER  = GND
  N19  GND_N19  POWER  = GND
  N21  IV12D_N21  POWER  = P1V2_AUX
  N22  PV33D_N22  POWER  = P3V3_AUX
  N23  \gpion1||ndcd2\  BI  = LED_POSTCODE_1
  N24  \gpion3||nri2\  BI  = LED_POSTCODE_3
  N25  \gpion2||ndsr2\  BI  = LED_POSTCODE_2
  N26  \gpion6||txd2\  BI  = LED_POSTCODE_6
  P1  MDQ5  BI  = M_BMC_DDR4_DQ<5>
  P2  MDQ6  BI  = M_BMC_DDR4_DQ<6>
  P3  MDQ7  BI  = M_BMC_DDR4_DQ<7>
  P4  GND_P4  POWER  = GND
  P5  MIOZ  BI  = IBMC_MIOZ
  P6  MVDD_P6  POWER  = P1V2_AUX
  P8  IV10D_P8  POWER  = P1V0_AUX
  P9  GND_P9  POWER  = GND
  P10  GND_P10  POWER  = GND
  P11  IV10D_P11  POWER  = P1V0_AUX
  P12  PV18D_P12  POWER  = P1V8_AUX
  P13  PV18D_SLI_P13  POWER  = P1V8_AUX
  P14  IV12D_P14  POWER  = P1V2_AUX
  P15  GND_P15  POWER  = GND
  P16  GND_P16  POWER  = GND
  P17  GND_P17  POWER  = GND
  P18  GND_P18  POWER  = GND
  P19  GND_P19  POWER  = GND
  P21  IV12D_P21  POWER  = P1V2_AUX
  P22  PV33D_P22  POWER  = P3V3_AUX
  P23  \gpios6||txd11\  BI  = RST_PCA9548_SENSOR_R_N
  P24  \gpios5||rxd10\  BI  = H_CPU1_PROCHOT_LVC1_N
  P25  \gpion0||ncts2\  BI  = LED_POSTCODE_0
  P26  \gpion4||ndtr2\  BI  = LED_POSTCODE_4
  R1  MDQ4  BI  = M_BMC_DDR4_DQ<4>
  R2  GND_R2  POWER  = GND
  R3  MDQ3  BI  = M_BMC_DDR4_DQ<3>
  R4  MDQ1  BI  = M_BMC_DDR4_DQ<1>
  R5  MDM1  OUT  = M_BMC_DDR4_MDM1
  R6  MVDD_R6  POWER  = P1V2_AUX
  R8  GND_R8  POWER  = GND
  R9  IV10D_R9  POWER  = P1V0_AUX
  R10  IV10D_R10  POWER  = P1V0_AUX
  R11  GND_R11  POWER  = GND
  R12  PV18D_R12  POWER  = P1V8_AUX
  R13  PV18D_SLI_R13  POWER  = P1V8_AUX
  R14  IV12D_R14  POWER  = P1V2_AUX
  R15  GND_R15  POWER  = GND
  R16  GND_R16  POWER  = GND
  R17  GND_R17  POWER  = GND
  R18  GND_R18  POWER  = GND
  R19  GND_R19  POWER  = GND
  R21  IV12D_R21  POWER  = P1V2_AUX
  R22  PV33D_R22  POWER  = P3V3_AUX
  R23  \gpios0||mdc1\  BI  = IRQ_BMC_PCH_NMI_N
  R24  \gpios3||oscclk\  BI  = FM_TPM_PRSNT_1_N
  R25  GND_R25  POWER  = GND
  R26  \gpios4||txd10\  BI  = FM_BMC_DEBUG_SW_N
  T1  \mdqs0#\  BI  = M_BMC_DDR4_DQS0_N
  T2  MDQS0  BI  = M_BMC_DDR4_DQS0_P
  T3  MDQ0  BI  = M_BMC_DDR4_DQ<0>
  T4  GND_T4  POWER  = GND
  T5  MVREF_T5  POWER  = P0V6_DDR_VREF_AUX
  T6  MVDD_T6  POWER  = P1V2_AUX
  T8  DP_VCC10A  POWER  = P1V0_STBY_DP_VCC10A
  T9  RC_VCC10A  POWER  = P1V0_STBY_PE_VCC10A
  T10  PE_VCC10A  POWER  = P1V0_STBY_RC_VCC10A
  T11  GND_T11  POWER  = GND
  T12  GND_T12  POWER  = GND
  T13  PV18D_SLI_T13  POWER  = P1V8_AUX
  T14  IV12D_T14  POWER  = P1V2_AUX
  T15  GND_T15  POWER  = GND
  T16  GND_T16  POWER  = GND
  T17  GND_T17  POWER  = GND
  T18  GND_T18  POWER  = GND
  T19  GND_T19  POWER  = GND
  T21  IV12D_T21  POWER  = P1V2_AUX
  T22  PV33D_T22  POWER  = P3V3_AUX
  T23  \gpior5||tach13\  BI  = PWRGD_PCH_PWROK
  T24  \gpios7||rxd11\  BI  = BMC_CPLD_GPIO_2_R1
  T25  \gpios1||mdio1\  BI  = BMC_MONITER
  T26  \gpios2||pewake#\  BI  = FM_THERMTRIP_DLY_LVC1_R_N
  U1  MDQ2  BI  = M_BMC_DDR4_DQ<2>
  U2  GND_U2  POWER  = GND
  U3  MDQ15  BI  = M_BMC_DDR4_DQ<15>
  U4  MDQ13  BI  = M_BMC_DDR4_DQ<13>
  U5  MVREF_U5  POWER  = P0V6_DDR_VREF_AUX
  U6  PV18D_U6  POWER  = P1V8_AUX
  U8  GND_U8  POWER  = GND
  U9  GND_U9  POWER  = GND
  U10  GND_U10  POWER  = GND
  U11  GND_U11  POWER  = GND
  U12  GND_U12  POWER  = GND
  U13  PV18D_SLI_U13  POWER  = P1V8_AUX
  U14  GND_U14  POWER  = GND
  U15  IV12D_U15  POWER  = P1V2_AUX
  U16  IV12D_U16  POWER  = P1V2_AUX
  U17  IV12D_U17  POWER  = P1V2_AUX
  U18  IV12D_U18  POWER  = P1V2_AUX
  U19  GND_U19  POWER  = GND
  U21  I3CVDDL2  POWER  = P1V2_P1V0_I3C_VDDL2
  U22  GND_U22  POWER  = GND
  U23  GND_U23  POWER  = GND
  U24  \gpior1||tach9\  BI  = IRQ_UV_DETECT_N
  U25  \gpior4||tach12\  BI  = IRQ_CPU1_VRHOT_N
  U26  \gpior7||tach15\  BI  = FM_BIOS_POST_CMPLT_BMC_N
  V1  \mdqs1#\  BI  = M_BMC_DDR4_DQS1_N
  V2  MDQS1  BI  = M_BMC_DDR4_DQS1_P
  V3  MDQ9  BI  = M_BMC_DDR4_DQ<9>
  V4  MDQ14  BI  = M_BMC_DDR4_DQ<14>
  V5  GND_V5  POWER  = GND
  V6  PV18D_V6  POWER  = P1V8_AUX
  V8  DP_VCC18A  POWER  = P1V8_STBY_DP_VCC18A
  V9  RC_VCC18A  POWER  = P1V8_STBY_PE_VCC18A
  V10  PE_VCC18A  POWER  = P1V8_STBY_RC_VCC18A
  V11  GND_V11  POWER  = GND
  V12  GND_V12  POWER  = GND
  V13  PV18D_SLI_V13  POWER  = P1V8_AUX
  V14  GND_V14  POWER  = GND
  V15  GND_V15  POWER  = GND
  V16  GND_V16  POWER  = GND
  V17  GND_V17  POWER  = GND
  V18  GND_V18  POWER  = GND
  V19  GND_V19  POWER  = GND
  V21  DACAV33_V21  POWER  = P3V3_STBY_DACAV33
  V22  I3CVDDL1  POWER  = P1V2_P1V0_I3C_VDDL1
  V23  BATVDD  POWER  = P3V3_RTC_AUX
  V24  \gpior2||tach10\  BI  = IRQ_OC_DETECT_EN_N
  V25  \gpior0||tach8\  BI  = IRQ_OC_DETECT_N
  V26  \gpior3||tach11\  BI  = IRQ_CPU0_VRHOT_N
  W1  MDQ10  BI  = M_BMC_DDR4_DQ<10>
  W2  MDQ8  BI  = M_BMC_DDR4_DQ<8>
  W3  MDQ11  BI  = M_BMC_DDR4_DQ<11>
  W4  MDQ12  BI  = M_BMC_DDR4_DQ<12>
  W5  GND_W5  POWER  = GND
  W6  GND_W6  POWER  = GND
  W8  GND_W8  POWER  = GND
  W9  GND_W9  POWER  = GND
  W10  GND_W10  POWER  = GND
  W11  GND_W11  POWER  = GND
  W12  GND_W12  POWER  = GND
  W13  PV18D_SLI_W13  POWER  = P1V8_AUX
  W14  PV18D_SLI_W14  POWER  = P1V8_AUX
  W15  LPVDD  POWER  = PGPPA_BMC_AUX
  W16  PV33D_W16  POWER  = P3V3_AUX
  W17  PV33D_W17  POWER  = P3V3_AUX
  W18  PV33D_W18  POWER  = P3V3_AUX
  W19  PV33D_W19  POWER  = P3V3_AUX
  W21  DACAV33_W21  POWER  = P3V3_STBY_DACAV33
  W22  GND_W22  POWER  = GND
  W23  \gpiop4||pwm12||thruin2\  BI  = BMC_PWR_LED
  W24  \gpiop1||pwm9||thruout0\  BI  = SYS_BMC_PWRBTN_R1_N
  W25  GND_W25  POWER  = GND
  W26  \gpior6||tach14\  BI  = PWRGD_CPUPWRGD_LVC1
  Y1  \gpio18e0||emmcdat4||fwspi18cs#||vbcs#\  BI  = NC
  Y2  \gpio18e1||emmcdat5||fwspi18ck||vbck\  BI  = NC
  Y3  \gpio18e2||emmcdat6||fwspi18mosi||vbmosi\  BI  = NC
  Y4  \gpio18e3||emmcdat7||fwspi18miso||vbmiso\  BI  = NC
  Y5  \gpio18d4||emmcdat2\  BI  = NC
  Y6  GND_Y6  POWER  = GND
  Y21  ADCAV33_Y21  POWER  = A_BMC_ADCAV33
  Y22  GND_Y22  POWER  = GND
  Y23  \gpiop7||pwm15||hbled#\  BI  = BMC_HEARTBEAT_N
  Y24  \gpioq2||tach2\  BI  = GPU_NVS_PWR_BRAKE_R_N
  Y25  \gpioq6||tach6\  BI  = FM_PCH_BEEP_LED
  Y26  \gpioq4||tach4\  BI  = FM_HDD_LED_N

U6  74LVC2G07DW7  74LVC2G07DW-7 IC  pkg SOT363_0-65_2X1-25XC  page 22
  1  \1a\  IN  = PWRGD_P1V0_AUX_DELAY
  2  GND  POWER  = GND
  3  \2a\  IN  = RST_SRST_PLD_BMC_R1_N
  4  \2y\  OUT  = RST_SRST_PLD_BMC_BUF_N
  5  VCC  POWER  = P3V3_AUX
  6  \1y\  OUT  = PWRGD_P1V0_AUX_DELAY_BUF

U7  NC7SB3157  NC7SB3157P6X IC  pkg SMLF  page 31
  1  B1  BI  = SPA_SOUT_SW_DBG_R
  2  GND  POWER  = GND
  3  B0  BI  = UART_SYS_DBG_TX_R
  4  A  BI  = SPA_SOUT_SW_BUF_R
  5  VCC  POWER  = P3V3_AUX
  6  S  IN  = FM_DBG_SW_N

U8  74LVC1G126SE7  74LVC1G126SE-7 IC  pkg SOT353_0-65_2X1-25  page 49
  1  OE  IN  = BMC_ID_BEEP_SEL
  2  A  IN  = PCH_BEEP_LED
  3  GND  POWER  = GND
  4  Y  OUT  = BEEP_LED
  5  VCC  POWER  = P3V3_AUX

U9  MC74VHC1G32DTT1G  IC  pkg SOT23-5_0-95_3X1-5  page 49
  1  IN_B  IN  = BEEP_LED
  2  IN_A  IN  = FM_ID_R_LED
  3  GND  POWER  = GND
  4  OUT_Y  OUT  = ID_LED_BUF
  5  VCC  POWER  = P3V3_AUX

U10  NCP380HSNAJAAT1G  IC  pkg TSOP6XE  page 28
  1  \in\  POWER  = P5V_AUX
  2  GND  POWER  = GND
  3  EN  IN  = USB_OC0_EN
  4  FLAG_N  OUT  = USB_OC0_REAR_N
  5  ILIM  IN  = USB_OC0_ILIM
  6  \out\  OUT  = P5V_USB_REAR

U11  BAT54C  IC  pkg SOT23_123  page 27
  1  B  IN  = FM_BMC_ONCTL_R_N
  2  A  IN  = UART_BMC_5_TXD_R
  3  C  BI  = FM_BMC_DISABLE

U12  MOSFET_N  BSS138K IC  pkg SMLF  page 22
  D  DRAIN  OUT  = RST_BMC_EXTRST_R1_N
  G  GATE  IN  = RST_BMC_SELF_HW_D_C
  S  SOURCE  BI  = GND

U13  MC74VHC1G07DFT2G  EMPTY  pkg SC70-5XA  page 22
  1  NC1  TRI  = NC
  2  IN_A  IN  = RST_BMC_SRST_BUF_R1_N
  3  GND  POWER  = GND
  4  OUT_Y  OUT  = RST_BMC_EXTRST_R1_N
  5  VCC  POWER  = P3V3_AUX

U14  AP22811AW57  AP22811AW5-7 IC  pkg SOT25-5_0-95_3X1-6  page 52
  1  \out\  OUT  = P3V3_RGM
  2  GND  POWER  = GND
  3  \flg#\  OCA  = TP_U14_FLAG_N
  4  EN  IN  = EN_P3V3_RGM_R
  5  \in\  IN  = P3V3_AUX

U15  74LVC1G08GW  IC  pkg SM  page 15
  1  B  BI  = SYS_BMC_PWRBTN_R_N
  2  A  BI  = PWR_BTN_BMC_N
  3  GND  POWER  = GND
  4  Y  BI  = SYS_PWRBTN_N
  5  VCC  POWER  = P3V3_AUX

U16  74LVC1G07GW  EMPTY  pkg SOT353_Q  page 50
  1  NC  TRI  = NC_U16_P1
  2  A  IN  = REAR_AC_PWR_BTN_N
  3  GND  POWER  = GND
  4  Y  OCA  = AC_PWR_BTN_R1_N
  5  VCC  POWER  = P3V3_AUX

U17  MX25L51245GMI10G  MX25L51245GMI-10G EMPTY  pkg SOP16_1-27_10-3X7-52  page 45
  1  NC_SIO3  BI  = SPI_PCH_IO3_FLASH_R1
  2  VCC  POWER  = P3V3_AUX
  3  \reset#\  BI  = RST_SPI_PCH_FLASH_R1_N
  4  NC1  TRI  = TP_J40_4
  5  DNU1  TRI  = TP_J40_5
  6  DNU2  TRI  = TP_J40_6
  7  \cs#\  BI  = SPI_PCH_CS0_FLASH_R1_N
  8  SO_SIO1  BI  = SPI_PCH_IO1_FLASH_R1
  9  \wp#_sio2\  BI  = SPI_PCH_IO2_FLASH_R1
  10  GND  POWER  = GND
  11  DNU3  TRI  = TP_J40_11
  12  DNU4  TRI  = TP_J40_12
  13  NC2  TRI  = TP_J40_13
  14  NC3  TRI  = TP_J40_14
  15  SI_SIO0  BI  = SPI_PCH_IO0_FLASH_R1
  16  SCLK  IN  = SPI_PCH_CLK_FLASH_R1

U18  74LVC1G08GW  IC  pkg SM  page 52
  1  B  BI  = PWRGD_P5V_AUX
  2  A  BI  = PWRGD_P1V8_AUX_R2
  3  GND  POWER  = GND
  4  Y  BI  = EN_P3V3_RGM
  5  VCC  POWER  = P3V3_LDO

U19  M24128BWDW6TP  M24128-BWDW6TP IC  pkg TSSOP8_0-65_3X4-4XG  page 26
  1  E0  IN  = FRU_E0
  2  E1  IN  = FRU_E1
  3  E2  IN  = FRU_E2
  4  VSS  POWER  = GND
  5  SDA  BI  = SMB_BMC_MM16_R2_SDA
  6  SCL  IN  = SMB_BMC_MM16_R2_SCL
  7  \wc#\  IN  = PD_FRU_WC_N
  8  VCC  POWER  = P3V3_AUX

U20  NC7SB3157  NC7SB3157P6X IC  pkg SMLF  page 31
  1  B1  BI  = SPA_SIN_SW_DBG_R
  2  GND  POWER  = GND
  3  B0  BI  = UART_SYS_DBG_RX_R
  4  A  BI  = SPA_SIN_SW_BUF_R
  5  VCC  POWER  = P3V3_AUX
  6  S  IN  = FM_DBG_SW_N
